(kicad_pcb
	(version 20260206)
	(generator "pcbnew")
	(generator_version "10.0")
	(general
		(thickness 1.6)
		(legacy_teardrops no)
	)
	(paper "A4")
	(title_block
		(title "01162023_DA0F0TEBIF0_F0T_Expander_BD_F_brd_V02_OCP.brd")
		(comment 1 "Grand Teton / footprints 2864-2869 of 9728")
	)
	(layers
		(0 "F.Cu" signal "TOP")
		(4 "In1.Cu" signal "GND")
		(6 "In2.Cu" signal "VCC")
		(8 "In3.Cu" signal "VCC1")
		(10 "In4.Cu" signal "GND1")
		(12 "In5.Cu" signal "IN1")
		(14 "In6.Cu" signal "GND2")
		(16 "In7.Cu" signal "IN2")
		(18 "In8.Cu" signal "GND3")
		(20 "In9.Cu" signal "IN3")
		(22 "In10.Cu" signal "GND4")
		(24 "In11.Cu" signal "IN4")
		(26 "In12.Cu" signal "GND5")
		(28 "In13.Cu" signal "IN5")
		(30 "In14.Cu" signal "GND6")
		(32 "In15.Cu" signal "IN6")
		(34 "In16.Cu" signal "GND7")
		(2 "B.Cu" signal "BOTTOM")
		(9 "F.Adhes" user "F.Adhesive")
		(11 "B.Adhes" user "B.Adhesive")
		(13 "F.Paste" user "Package Geometry/Pastemask Top")
		(15 "B.Paste" user "Package Geometry/Pastemask Bottom")
		(5 "F.SilkS" user "Ref Des/Silkscreen Top")
		(7 "B.SilkS" user "Ref Des/Silkscreen Bottom")
		(1 "F.Mask" user "Board Geometry/Soldermask Top")
		(3 "B.Mask" user "Board Geometry/Soldermask Bottom")
		(17 "Dwgs.User" user "User.Drawings")
		(19 "Cmts.User" user "User.Comments")
		(21 "Eco1.User" user "User.Eco1")
		(23 "Eco2.User" user "User.Eco2")
		(25 "Edge.Cuts" user "Board Geometry/Outline")
		(27 "Margin" user)
		(31 "F.CrtYd" user "Package Geometry/Place Bound Top")
		(29 "B.CrtYd" user "Package Geometry/Place Bound Bottom")
		(35 "F.Fab" user "Ref Des/Assembly Top")
		(33 "B.Fab" user "Ref Des/Assembly Bottom")
	)
	(footprint ""
		(layer "F.Cu")
		(at 382.786636 -226.435666 90)
		(property "Reference" "Y3"
			(at -2.510536 -0.262636 0)
			(unlocked yes)
			(layer "F.SilkS")
			(effects
				(font
					(size 0.7874 0.5842)
					(thickness 0.1524)
				)
				(justify left)
			)
		)
		(property "Value" ""
			(at 0 0 90)
			(layer "F.Fab")
			(effects
				(font
					(size 1.27 1.27)
				)
			)
		)
		(duplicate_pad_numbers_are_jumpers no)
		(fp_line
			(start 1.6002 -1.9558)
			(end 1.6002 1.9558)
			(stroke
				(width 0.1524)
				(type default)
			)
			(layer "F.SilkS")
		)
		(fp_line
			(start -1.6002 -1.9558)
			(end 1.6002 -1.9558)
			(stroke
				(width 0.1524)
				(type default)
			)
			(layer "F.SilkS")
		)
		(fp_line
			(start 1.6002 1.9558)
			(end -1.6002 1.9558)
			(stroke
				(width 0.1524)
				(type default)
			)
			(layer "F.SilkS")
		)
		(fp_line
			(start -1.6002 1.9558)
			(end -1.6002 -1.9558)
			(stroke
				(width 0.1524)
				(type default)
			)
			(layer "F.SilkS")
		)
		(fp_poly
			(pts
				(xy -1.7145 -1.0668) (xy -2.8067 -1.651) (xy -2.8067 -0.5842)
			)
			(stroke
				(width 0)
				(type default)
			)
			(fill yes)
			(layer "F.SilkS")
		)
		(fp_line
			(start 1.299972 -1.649984)
			(end 1.299972 1.649984)
			(stroke
				(width 0.1)
				(type default)
			)
			(layer "F.Fab")
		)
		(fp_line
			(start -1.299972 -1.649984)
			(end 1.299972 -1.649984)
			(stroke
				(width 0.1)
				(type default)
			)
			(layer "F.Fab")
		)
		(fp_line
			(start 1.299972 1.649984)
			(end -1.299972 1.649984)
			(stroke
				(width 0.1)
				(type default)
			)
			(layer "F.Fab")
		)
		(fp_line
			(start -1.299972 1.649984)
			(end -1.299972 -1.649984)
			(stroke
				(width 0.1)
				(type default)
			)
			(layer "F.Fab")
		)
		(fp_poly
			(pts
				(xy -1.7145 -1.0668) (xy -2.8067 -1.651) (xy -2.8067 -0.5842)
			)
			(stroke
				(width 0)
				(type default)
			)
			(fill yes)
			(layer "F.Fab")
		)
		(pad "1" smd rect
			(at -0.849884 -1.100074 90)
			(size 1.2192 1.4224)
			(layers "F.Cu" "F.Mask" "F.Paste")
			(net "OSC_SDB_IN")
		)
		(pad "2" smd rect
			(at -0.849884 1.100074 90)
			(size 1.2192 1.4224)
			(layers "F.Cu" "F.Mask" "F.Paste")
			(net "GND")
		)
		(pad "3" smd rect
			(at 0.849884 1.100074 90)
			(size 1.2192 1.4224)
			(layers "F.Cu" "F.Mask" "F.Paste")
			(net "OSC_SDB_OUT")
		)
		(pad "4" smd rect
			(at 0.849884 -1.100074 90)
			(size 1.2192 1.4224)
			(layers "F.Cu" "F.Mask" "F.Paste")
			(net "GND")
		)
	)
	(footprint ""
		(layer "F.Cu")
		(at 263.381998 -338.85251)
		(property "Reference" "U449"
			(at -5.058664 -1.037082 0)
			(unlocked yes)
			(layer "F.SilkS")
			(effects
				(font
					(size 0.7874 0.5842)
					(thickness 0.1524)
				)
				(justify left)
			)
		)
		(property "Value" ""
			(at 0 0 0)
			(layer "F.Fab")
			(effects
				(font
					(size 1.27 1.27)
				)
			)
		)
		(duplicate_pad_numbers_are_jumpers no)
		(fp_line
			(start -1.868424 -1.519936)
			(end -1.868424 1.519936)
			(stroke
				(width 0.1524)
				(type default)
			)
			(layer "F.SilkS")
		)
		(fp_line
			(start -1.868424 1.519936)
			(end 1.868424 1.519936)
			(stroke
				(width 0.1524)
				(type default)
			)
			(layer "F.SilkS")
		)
		(fp_line
			(start 1.868424 -1.519936)
			(end -1.868424 -1.519936)
			(stroke
				(width 0.1524)
				(type default)
			)
			(layer "F.SilkS")
		)
		(fp_line
			(start 1.868424 1.519936)
			(end 1.868424 -1.519936)
			(stroke
				(width 0.1524)
				(type default)
			)
			(layer "F.SilkS")
		)
		(fp_line
			(start -0.700024 -1.519936)
			(end -0.700024 1.519936)
			(stroke
				(width 0.1)
				(type default)
			)
			(layer "F.Fab")
		)
		(fp_line
			(start -0.700024 1.519936)
			(end 0.700024 1.519936)
			(stroke
				(width 0.1)
				(type default)
			)
			(layer "F.Fab")
		)
		(fp_line
			(start 0.700024 -1.519936)
			(end -0.700024 -1.519936)
			(stroke
				(width 0.1)
				(type default)
			)
			(layer "F.Fab")
		)
		(fp_line
			(start 0.700024 1.519936)
			(end 0.700024 -1.519936)
			(stroke
				(width 0.1)
				(type default)
			)
			(layer "F.Fab")
		)
		(pad "1" smd rect
			(at -1.18491 -0.94996 270)
			(size 0.6096 1.0668)
			(layers "F.Cu" "F.Mask" "F.Paste")
			(net "OC_P2V5_COMP")
		)
		(pad "2" smd rect
			(at -1.18491 0.94996 270)
			(size 0.6096 1.0668)
			(layers "F.Cu" "F.Mask" "F.Paste")
			(net "GND")
		)
		(pad "3" smd rect
			(at 1.18491 0 270)
			(size 0.6096 1.0668)
			(layers "F.Cu" "F.Mask" "F.Paste")
			(net "Net_9325")
		)
	)
	(footprint ""
		(layer "F.Cu")
		(at 30.438344 -250.070874 -90)
		(property "Reference" "R1152"
			(at 0 0 270)
			(layer "F.SilkS")
			(hide yes)
			(effects
				(font
					(size 1.27 1.27)
				)
			)
		)
		(property "Value" ""
			(at 0 0 270)
			(layer "F.Fab")
			(effects
				(font
					(size 1.27 1.27)
				)
			)
		)
		(duplicate_pad_numbers_are_jumpers no)
		(fp_line
			(start -0.7874 0.4064)
			(end -0.7874 -0.4064)
			(stroke
				(width 0.1524)
				(type default)
			)
			(layer "F.SilkS")
		)
		(fp_line
			(start 0.7874 0.4064)
			(end -0.7874 0.4064)
			(stroke
				(width 0.1524)
				(type default)
			)
			(layer "F.SilkS")
		)
		(fp_line
			(start -0.7874 -0.4064)
			(end 0.7874 -0.4064)
			(stroke
				(width 0.1524)
				(type default)
			)
			(layer "F.SilkS")
		)
		(fp_line
			(start 0.7874 -0.4064)
			(end 0.7874 0.4064)
			(stroke
				(width 0.1524)
				(type default)
			)
			(layer "F.SilkS")
		)
		(fp_line
			(start -0.67945 0.3048)
			(end -0.67945 -0.305054)
			(stroke
				(width 0.1)
				(type default)
			)
			(layer "F.Fab")
		)
		(fp_line
			(start -0.12065 0.3048)
			(end -0.67945 0.3048)
			(stroke
				(width 0.1)
				(type default)
			)
			(layer "F.Fab")
		)
		(fp_line
			(start 0.120396 0.3048)
			(end 0.120396 0.2794)
			(stroke
				(width 0.1)
				(type default)
			)
			(layer "F.Fab")
		)
		(fp_line
			(start 0.67945 0.3048)
			(end 0.120396 0.3048)
			(stroke
				(width 0.1)
				(type default)
			)
			(layer "F.Fab")
		)
		(fp_line
			(start -0.12065 0.2794)
			(end -0.12065 0.3048)
			(stroke
				(width 0.1)
				(type default)
			)
			(layer "F.Fab")
		)
		(fp_line
			(start 0.120396 0.2794)
			(end -0.12065 0.2794)
			(stroke
				(width 0.1)
				(type default)
			)
			(layer "F.Fab")
		)
		(fp_line
			(start -0.12065 -0.2794)
			(end 0.12065 -0.2794)
			(stroke
				(width 0.1)
				(type default)
			)
			(layer "F.Fab")
		)
		(fp_line
			(start 0.12065 -0.2794)
			(end 0.12065 -0.3048)
			(stroke
				(width 0.1)
				(type default)
			)
			(layer "F.Fab")
		)
		(fp_line
			(start 0.12065 -0.3048)
			(end 0.67945 -0.3048)
			(stroke
				(width 0.1)
				(type default)
			)
			(layer "F.Fab")
		)
		(fp_line
			(start 0.67945 -0.3048)
			(end 0.67945 0.3048)
			(stroke
				(width 0.1)
				(type default)
			)
			(layer "F.Fab")
		)
		(fp_line
			(start -0.67945 -0.305054)
			(end -0.12065 -0.305054)
			(stroke
				(width 0.1)
				(type default)
			)
			(layer "F.Fab")
		)
		(fp_line
			(start -0.12065 -0.305054)
			(end -0.12065 -0.2794)
			(stroke
				(width 0.1)
				(type default)
			)
			(layer "F.Fab")
		)
		(pad "1" smd circle
			(at -0.40005 0 270)
			(size 0 0)
			(layers "F.Cu" "F.Mask" "F.Paste")
			(net "PEX0_MODE_SEL0")
		)
		(pad "2" smd circle
			(at 0.40005 0 270)
			(size 0 0)
			(layers "F.Cu" "F.Mask" "F.Paste")
			(net "P1V8_PEX")
		)
	)
	(footprint ""
		(layer "F.Cu")
		(at 168.343834 -48.93691 180)
		(property "Reference" "R567"
			(at 0 0 180)
			(layer "F.SilkS")
			(hide yes)
			(effects
				(font
					(size 1.27 1.27)
				)
			)
		)
		(property "Value" ""
			(at 0 0 180)
			(layer "F.Fab")
			(effects
				(font
					(size 1.27 1.27)
				)
			)
		)
		(duplicate_pad_numbers_are_jumpers no)
		(fp_line
			(start 0.7874 0.4064)
			(end -0.7874 0.4064)
			(stroke
				(width 0.1524)
				(type default)
			)
			(layer "F.SilkS")
		)
		(fp_line
			(start 0.7874 -0.4064)
			(end 0.7874 0.4064)
			(stroke
				(width 0.1524)
				(type default)
			)
			(layer "F.SilkS")
		)
		(fp_line
			(start -0.7874 0.4064)
			(end -0.7874 -0.4064)
			(stroke
				(width 0.1524)
				(type default)
			)
			(layer "F.SilkS")
		)
		(fp_line
			(start -0.7874 -0.4064)
			(end 0.7874 -0.4064)
			(stroke
				(width 0.1524)
				(type default)
			)
			(layer "F.SilkS")
		)
		(fp_line
			(start 0.67945 0.3048)
			(end 0.120396 0.3048)
			(stroke
				(width 0.1)
				(type default)
			)
			(layer "F.Fab")
		)
		(fp_line
			(start 0.67945 -0.3048)
			(end 0.67945 0.3048)
			(stroke
				(width 0.1)
				(type default)
			)
			(layer "F.Fab")
		)
		(fp_line
			(start 0.12065 -0.2794)
			(end 0.12065 -0.3048)
			(stroke
				(width 0.1)
				(type default)
			)
			(layer "F.Fab")
		)
		(fp_line
			(start 0.12065 -0.3048)
			(end 0.67945 -0.3048)
			(stroke
				(width 0.1)
				(type default)
			)
			(layer "F.Fab")
		)
		(fp_line
			(start 0.120396 0.3048)
			(end 0.120396 0.2794)
			(stroke
				(width 0.1)
				(type default)
			)
			(layer "F.Fab")
		)
		(fp_line
			(start 0.120396 0.2794)
			(end -0.12065 0.2794)
			(stroke
				(width 0.1)
				(type default)
			)
			(layer "F.Fab")
		)
		(fp_line
			(start -0.12065 0.3048)
			(end -0.67945 0.3048)
			(stroke
				(width 0.1)
				(type default)
			)
			(layer "F.Fab")
		)
		(fp_line
			(start -0.12065 0.2794)
			(end -0.12065 0.3048)
			(stroke
				(width 0.1)
				(type default)
			)
			(layer "F.Fab")
		)
		(fp_line
			(start -0.12065 -0.2794)
			(end 0.12065 -0.2794)
			(stroke
				(width 0.1)
				(type default)
			)
			(layer "F.Fab")
		)
		(fp_line
			(start -0.12065 -0.305054)
			(end -0.12065 -0.2794)
			(stroke
				(width 0.1)
				(type default)
			)
			(layer "F.Fab")
		)
		(fp_line
			(start -0.67945 0.3048)
			(end -0.67945 -0.305054)
			(stroke
				(width 0.1)
				(type default)
			)
			(layer "F.Fab")
		)
		(fp_line
			(start -0.67945 -0.305054)
			(end -0.12065 -0.305054)
			(stroke
				(width 0.1)
				(type default)
			)
			(layer "F.Fab")
		)
		(pad "1" smd circle
			(at -0.40005 0 180)
			(size 0 0)
			(layers "F.Cu" "F.Mask" "F.Paste")
			(net "SMB_BIC_I2C6_MUX_SSD_0_7_ADC_R_SDA")
		)
		(pad "2" smd circle
			(at 0.40005 0 180)
			(size 0 0)
			(layers "F.Cu" "F.Mask" "F.Paste")
			(net "SMB_SSD5_ADC_SDA")
		)
	)
	(footprint ""
		(layer "F.Cu")
		(at 177.33518 -195.208652)
		(property "Reference" "U50"
			(at -1.36398 -3.367278 0)
			(unlocked yes)
			(layer "F.SilkS")
			(effects
				(font
					(size 0.7874 0.5842)
					(thickness 0.1524)
				)
				(justify left)
			)
		)
		(property "Value" ""
			(at 0 0 0)
			(layer "F.Fab")
			(effects
				(font
					(size 1.27 1.27)
				)
			)
		)
		(duplicate_pad_numbers_are_jumpers no)
		(fp_line
			(start -1.868932 -2.549906)
			(end -1.868932 2.549906)
			(stroke
				(width 0.1524)
				(type default)
			)
			(layer "F.SilkS")
		)
		(fp_line
			(start -1.868932 2.549906)
			(end 1.868932 2.549906)
			(stroke
				(width 0.1524)
				(type default)
			)
			(layer "F.SilkS")
		)
		(fp_line
			(start -1.025906 -2.549906)
			(end -1.868932 -2.549906)
			(stroke
				(width 0.1524)
				(type default)
			)
			(layer "F.SilkS")
		)
		(fp_line
			(start 0 -1.524)
			(end -1.025906 -2.549906)
			(stroke
				(width 0.1524)
				(type default)
			)
			(layer "F.SilkS")
		)
		(fp_line
			(start 1.025906 -2.549906)
			(end 0 -1.524)
			(stroke
				(width 0.1524)
				(type default)
			)
			(layer "F.SilkS")
		)
		(fp_line
			(start 1.868932 -2.549906)
			(end 1.025906 -2.549906)
			(stroke
				(width 0.1524)
				(type default)
			)
			(layer "F.SilkS")
		)
		(fp_line
			(start 1.868932 2.549906)
			(end 1.868932 -2.549906)
			(stroke
				(width 0.1524)
				(type default)
			)
			(layer "F.SilkS")
		)
		(fp_poly
			(pts
				(xy -4.7752 -1.787398) (xy -4.7752 -2.803398) (xy -3.7592 -2.295398)
			)
			(stroke
				(width 0)
				(type default)
			)
			(fill yes)
			(layer "F.SilkS")
		)
		(fp_line
			(start -2.249932 -2.549906)
			(end -2.249932 2.549906)
			(stroke
				(width 0.1)
				(type default)
			)
			(layer "F.Fab")
		)
		(fp_line
			(start -2.249932 2.549906)
			(end 2.249932 2.549906)
			(stroke
				(width 0.1)
				(type default)
			)
			(layer "F.Fab")
		)
		(fp_line
			(start 2.249932 -2.549906)
			(end -2.249932 -2.549906)
			(stroke
				(width 0.1)
				(type default)
			)
			(layer "F.Fab")
		)
		(fp_line
			(start 2.249932 2.549906)
			(end 2.249932 -2.549906)
			(stroke
				(width 0.1)
				(type default)
			)
			(layer "F.Fab")
		)
		(fp_poly
			(pts
				(xy -4.7752 -1.787398) (xy -4.7752 -2.803398) (xy -3.7592 -2.295398)
			)
			(stroke
				(width 0)
				(type default)
			)
			(fill yes)
			(layer "F.Fab")
		)
		(pad "1" smd rect
			(at -2.800096 -2.275078 270)
			(size 0.3556 1.6002)
			(layers "F.Cu" "F.Mask" "F.Paste")
			(net "SPI_BIC1_CS0_LS01_N_DIR1")
		)
		(pad "2" smd rect
			(at -2.800096 -1.625092 270)
			(size 0.3556 1.6002)
			(layers "F.Cu" "F.Mask" "F.Paste")
			(net "SPI_BIC1_CLK_LS01_DIR2")
		)
		(pad "3" smd rect
			(at -2.800096 -0.975106 270)
			(size 0.3556 1.6002)
			(layers "F.Cu" "F.Mask" "F.Paste")
			(net "SPI_BIC1_CS0_LS01_N")
		)
		(pad "4" smd rect
			(at -2.800096 -0.32512 270)
			(size 0.3556 1.6002)
			(layers "F.Cu" "F.Mask" "F.Paste")
			(net "SPI_BIC1_CLK_LS01")
		)
		(pad "5" smd rect
			(at -2.800096 0.32512 270)
			(size 0.3556 1.6002)
			(layers "F.Cu" "F.Mask" "F.Paste")
			(net "SPI_BIC1_MOSI_LS01")
		)
		(pad "6" smd rect
			(at -2.800096 0.975106 270)
			(size 0.3556 1.6002)
			(layers "F.Cu" "F.Mask" "F.Paste")
			(net "SPI_BIC1_MISO_LS01")
		)
		(pad "7" smd rect
			(at -2.800096 1.625092 270)
			(size 0.3556 1.6002)
			(layers "F.Cu" "F.Mask" "F.Paste")
			(net "SPI_BIC1_MOSI_LS01_DIR3")
		)
		(pad "8" smd rect
			(at -2.800096 2.275078 270)
			(size 0.3556 1.6002)
			(layers "F.Cu" "F.Mask" "F.Paste")
			(net "SPI_BIC1_MISO_LS01_DIR4")
		)
		(pad "9" smd rect
			(at 2.800096 2.275078 270)
			(size 0.3556 1.6002)
			(layers "F.Cu" "F.Mask" "F.Paste")
			(net "SPI_BIC1_LS01_EN_R_N")
		)
		(pad "10" smd rect
			(at 2.800096 1.625092 270)
			(size 0.3556 1.6002)
			(layers "F.Cu" "F.Mask" "F.Paste")
			(net "GND")
		)
		(pad "11" smd rect
			(at 2.800096 0.975106 270)
			(size 0.3556 1.6002)
			(layers "F.Cu" "F.Mask" "F.Paste")
			(net "SPI_BIC1_MISO_R3")
		)
		(pad "12" smd rect
			(at 2.800096 0.32512 270)
			(size 0.3556 1.6002)
			(layers "F.Cu" "F.Mask" "F.Paste")
			(net "SPI_BIC1_MOSI_R3")
		)
		(pad "13" smd rect
			(at 2.800096 -0.32512 270)
			(size 0.3556 1.6002)
			(layers "F.Cu" "F.Mask" "F.Paste")
			(net "SPI_BIC1_CLK_R3")
		)
		(pad "14" smd rect
			(at 2.800096 -0.975106 270)
			(size 0.3556 1.6002)
			(layers "F.Cu" "F.Mask" "F.Paste")
			(net "SPI_BIC1_CS0_R2_N")
		)
		(pad "15" smd rect
			(at 2.800096 -1.625092 270)
			(size 0.3556 1.6002)
			(layers "F.Cu" "F.Mask" "F.Paste")
			(net "P3V3_AUX")
		)
		(pad "16" smd rect
			(at 2.800096 -2.275078 270)
			(size 0.3556 1.6002)
			(layers "F.Cu" "F.Mask" "F.Paste")
			(net "P1V8_PEX")
		)
	)
	(footprint ""
		(layer "F.Cu")
		(at 379.2474 -36.686998 90)
		(property "Reference" "C3670"
			(at 0 0 90)
			(layer "F.SilkS")
			(hide yes)
			(effects
				(font
					(size 1.27 1.27)
				)
			)
		)
		(property "Value" ""
			(at 0 0 90)
			(layer "F.Fab")
			(effects
				(font
					(size 1.27 1.27)
				)
			)
		)
		(duplicate_pad_numbers_are_jumpers no)
		(fp_line
			(start 0.7874 -0.4064)
			(end 0.7874 0.4064)
			(stroke
				(width 0.1524)
				(type default)
			)
			(layer "F.SilkS")
		)
		(fp_line
			(start -0.7874 -0.4064)
			(end 0.7874 -0.4064)
			(stroke
				(width 0.1524)
				(type default)
			)
			(layer "F.SilkS")
		)
		(fp_line
			(start 0.7874 0.4064)
			(end -0.7874 0.4064)
			(stroke
				(width 0.1524)
				(type default)
			)
			(layer "F.SilkS")
		)
		(fp_line
			(start -0.7874 0.4064)
			(end -0.7874 -0.4064)
			(stroke
				(width 0.1524)
				(type default)
			)
			(layer "F.SilkS")
		)
		(fp_line
			(start -0.12065 -0.305054)
			(end -0.12065 -0.2794)
			(stroke
				(width 0.1)
				(type default)
			)
			(layer "F.Fab")
		)
		(fp_line
			(start -0.67945 -0.305054)
			(end -0.12065 -0.305054)
			(stroke
				(width 0.1)
				(type default)
			)
			(layer "F.Fab")
		)
		(fp_line
			(start 0.67945 -0.3048)
			(end 0.67945 0.3048)
			(stroke
				(width 0.1)
				(type default)
			)
			(layer "F.Fab")
		)
		(fp_line
			(start 0.12065 -0.3048)
			(end 0.67945 -0.3048)
			(stroke
				(width 0.1)
				(type default)
			)
			(layer "F.Fab")
		)
		(fp_line
			(start 0.12065 -0.2794)
			(end 0.12065 -0.3048)
			(stroke
				(width 0.1)
				(type default)
			)
			(layer "F.Fab")
		)
		(fp_line
			(start -0.12065 -0.2794)
			(end 0.12065 -0.2794)
			(stroke
				(width 0.1)
				(type default)
			)
			(layer "F.Fab")
		)
		(fp_line
			(start 0.120396 0.2794)
			(end -0.12065 0.2794)
			(stroke
				(width 0.1)
				(type default)
			)
			(layer "F.Fab")
		)
		(fp_line
			(start -0.12065 0.2794)
			(end -0.12065 0.3048)
			(stroke
				(width 0.1)
				(type default)
			)
			(layer "F.Fab")
		)
		(fp_line
			(start 0.67945 0.3048)
			(end 0.120396 0.3048)
			(stroke
				(width 0.1)
				(type default)
			)
			(layer "F.Fab")
		)
		(fp_line
			(start 0.120396 0.3048)
			(end 0.120396 0.2794)
			(stroke
				(width 0.1)
				(type default)
			)
			(layer "F.Fab")
		)
		(fp_line
			(start -0.12065 0.3048)
			(end -0.67945 0.3048)
			(stroke
				(width 0.1)
				(type default)
			)
			(layer "F.Fab")
		)
		(fp_line
			(start -0.67945 0.3048)
			(end -0.67945 -0.305054)
			(stroke
				(width 0.1)
				(type default)
			)
			(layer "F.Fab")
		)
		(pad "1" smd circle
			(at -0.40005 0 90)
			(size 0 0)
			(layers "F.Cu" "F.Mask" "F.Paste")
			(net "P3V3_AUX")
		)
		(pad "2" smd circle
			(at 0.40005 0 90)
			(size 0 0)
			(layers "F.Cu" "F.Mask" "F.Paste")
			(net "GND")
		)
	)
)
